# TIMECARD (Time Appliance Project (Time Card)) — schematic netlist excerpt (pin names and nets, part order shuffled) for the footprints in the layout excerpt that follows; sources: Cadence DE-HDL packaged netlist, KiCad conversion of R4006-B0001-02_R01.brd

C213  CAPACITOR  0.1UF 10V 10%  pkg SMC_0402R_H022  page 14 : \1\ = XP2R5V_FPGA ; \2\ = SG
C58  CAPACITOR  10UF 25V 20%  pkg SMC_0805R_H057  page 21 : \1\ = XP5R0V_MAC ; \2\ = SG

(kicad_pcb
	(version 20260206)
	(generator "pcbnew")
	(generator_version "10.0")
	(general
		(thickness 1.6)
		(legacy_teardrops no)
	)
	(paper "A4")
	(title_block
		(title "timecard-production-celestica-r4006 — R4006-B0001-02_R01.brd")
		(comment 1 "Time Appliance Project (Time Card) / footprints 880-881 of 1113")
	)
	(layers
		(0 "F.Cu" signal "TOP")
		(4 "In1.Cu" signal "L02_GND1")
		(6 "In2.Cu" signal "L03_SIG1")
		(8 "In3.Cu" signal "L04_GND2")
		(10 "In4.Cu" signal "L05_VCC1")
		(12 "In5.Cu" signal "L06_VCC2")
		(14 "In6.Cu" signal "L07_GND3")
		(16 "In7.Cu" signal "L08_SIG2")
		(18 "In8.Cu" signal "L09_GND4")
		(2 "B.Cu" signal "BOTTOM")
		(9 "F.Adhes" user "F.Adhesive")
		(11 "B.Adhes" user "B.Adhesive")
		(13 "F.Paste" user "Package Geometry/Pastemask Top")
		(15 "B.Paste" user "Package Geometry/Pastemask Bottom")
		(5 "F.SilkS" user "Ref Des/Silkscreen Top")
		(7 "B.SilkS" user "Ref Des/Silkscreen Bottom")
		(1 "F.Mask" user "Board Geometry/Soldermask Top")
		(3 "B.Mask" user "Board Geometry/Soldermask Bottom")
		(17 "Dwgs.User" user "User.Drawings")
		(19 "Cmts.User" user "User.Comments")
		(21 "Eco1.User" user "User.Eco1")
		(23 "Eco2.User" user "User.Eco2")
		(25 "Edge.Cuts" user "Board Geometry/Outline")
		(27 "Margin" user)
		(31 "F.CrtYd" user "Package Geometry/Place Bound Top")
		(29 "B.CrtYd" user "Package Geometry/Place Bound Bottom")
		(35 "F.Fab" user "Ref Des/Assembly Top")
		(33 "B.Fab" user "Ref Des/Assembly Bottom")
	)
	(footprint ""
		(layer "B.Cu")
		(at 75.184 -73.152 -90)
		(property "Reference" "C58"
			(at -3.429 -0.34163 270)
			(unlocked yes)
			(layer "B.SilkS")
			(effects
				(font
					(size 0.7874 0.5842)
					(thickness 0.1524)
				)
				(justify mirror)
			)
		)
		(property "Value" "VAL*"
			(at -0.0762 3.134106 270)
			(unlocked yes)
			(layer "B.Fab")
			(hide yes)
			(effects
				(font
					(size 0.7874 0.5842)
					(thickness 0.1524)
				)
				(justify mirror)
			)
		)
		(property "Device Type" "CAPACITOR-G107-0F106-EM,10UF,2A"
			(at -0.0508 2.194306 270)
			(unlocked yes)
			(layer "B.Fab")
			(hide yes)
			(effects
				(font
					(size 0.7874 0.5842)
					(thickness 0.1524)
				)
				(justify mirror)
			)
		)
		(property "User Part Number" "PARTNUM*"
			(at -0.1016 5.013706 270)
			(unlocked yes)
			(layer "Cmts.User")
			(hide yes)
			(effects
				(font
					(size 0.7874 0.5842)
					(thickness 0.1524)
				)
				(justify mirror)
			)
		)
		(property "Tolerance" "TOL*"
			(at -0.0762 4.048506 270)
			(unlocked yes)
			(layer "Cmts.User")
			(hide yes)
			(effects
				(font
					(size 0.7874 0.5842)
					(thickness 0.1524)
				)
				(justify mirror)
			)
		)
		(duplicate_pad_numbers_are_jumpers no)
		(fp_line
			(start -1.5748 0.9398)
			(end -1.5748 -0.9398)
			(stroke
				(width 0.1)
				(type default)
			)
			(layer "B.SilkS")
		)
		(fp_line
			(start 1.5748 0.9398)
			(end -1.5748 0.9398)
			(stroke
				(width 0.1)
				(type default)
			)
			(layer "B.SilkS")
		)
		(fp_line
			(start -1.5748 -0.9398)
			(end 1.5748 -0.9398)
			(stroke
				(width 0.1)
				(type default)
			)
			(layer "B.SilkS")
		)
		(fp_line
			(start 1.5748 -0.9398)
			(end 1.5748 0.9398)
			(stroke
				(width 0.1)
				(type default)
			)
			(layer "B.SilkS")
		)
		(fp_rect
			(start 1.5748 0.9398)
			(end -1.5748 -0.9398)
			(stroke
				(width 0)
				(type default)
			)
			(fill no)
			(layer "B.CrtYd")
		)
		(fp_line
			(start -1.016 0.635)
			(end -1.016 -0.635)
			(stroke
				(width 0.1)
				(type default)
			)
			(layer "B.Fab")
		)
		(fp_line
			(start 1.016 0.635)
			(end -1.016 0.635)
			(stroke
				(width 0.1)
				(type default)
			)
			(layer "B.Fab")
		)
		(fp_line
			(start -1.016 -0.635)
			(end 1.016 -0.635)
			(stroke
				(width 0.1)
				(type default)
			)
			(layer "B.Fab")
		)
		(fp_line
			(start 1.016 -0.635)
			(end 1.016 0.635)
			(stroke
				(width 0.1)
				(type default)
			)
			(layer "B.Fab")
		)
		(pad "1" smd rect
			(at 0.8382 0 90)
			(size 0.9652 1.3716)
			(layers "B.Cu" "B.Mask" "B.Paste")
			(net "XP5R0V_MAC")
		)
		(pad "2" smd rect
			(at -0.8382 0 90)
			(size 0.9652 1.3716)
			(layers "B.Cu" "B.Mask" "B.Paste")
			(net "SG")
		)
		(zone
			(layer "B.Cu")
			(hatch none 0.5)
			(connect_pads
				(clearance 0)
			)
			(min_thickness 0.25)
			(keepout
				(tracks allowed)
				(vias not_allowed)
				(pads allowed)
				(copperpour not_allowed)
				(footprints allowed)
			)
			(placement
				(enabled no)
				(sheetname "")
			)
			(fill
				(thermal_gap 0.5)
				(thermal_bridge_width 0.5)
				(island_removal_mode 0)
			)
			(polygon
				(pts
					(xy 74.549 -72.9234) (xy 75.819 -72.9234) (xy 75.819 -73.3806) (xy 74.549 -73.3806)
				)
			)
		)
	)
	(footprint ""
		(layer "B.Cu")
		(at 102.84714 -35.323018 -90)
		(property "Reference" "C213"
			(at 1.668018 43.56989 270)
			(unlocked yes)
			(layer "B.SilkS")
			(effects
				(font
					(size 0.635 0.4064)
					(thickness 0.1524)
				)
				(justify mirror)
			)
		)
		(property "Value" "VAL*"
			(at 0 3.718306 270)
			(unlocked yes)
			(layer "B.Fab")
			(hide yes)
			(effects
				(font
					(size 0.7874 0.5842)
					(thickness 0.127)
				)
				(justify mirror)
			)
		)
		(property "Tolerance" "TOL*"
			(at 0 4.861306 270)
			(unlocked yes)
			(layer "Cmts.User")
			(hide yes)
			(effects
				(font
					(size 0.7874 0.5842)
					(thickness 0.127)
				)
				(justify mirror)
			)
		)
		(property "User Part Number" "PARTNUM*"
			(at 0 2.575306 270)
			(unlocked yes)
			(layer "Cmts.User")
			(hide yes)
			(effects
				(font
					(size 0.7874 0.5842)
					(thickness 0.127)
				)
				(justify mirror)
			)
		)
		(property "Device Type" "CAPACITOR-G105-0B104-CK,0.1UF,A"
			(at 0 1.432306 270)
			(unlocked yes)
			(layer "B.Fab")
			(hide yes)
			(effects
				(font
					(size 0.7874 0.5842)
					(thickness 0.127)
				)
				(justify mirror)
			)
		)
		(duplicate_pad_numbers_are_jumpers no)
		(fp_line
			(start -0.970026 0.4699)
			(end 0.970026 0.4699)
			(stroke
				(width 0.1)
				(type default)
			)
			(layer "B.SilkS")
		)
		(fp_line
			(start 0.970026 0.4699)
			(end 0.970026 -0.4699)
			(stroke
				(width 0.1)
				(type default)
			)
			(layer "B.SilkS")
		)
		(fp_line
			(start -0.970026 -0.4699)
			(end -0.970026 0.4699)
			(stroke
				(width 0.1)
				(type default)
			)
			(layer "B.SilkS")
		)
		(fp_line
			(start 0.970026 -0.4699)
			(end -0.970026 -0.4699)
			(stroke
				(width 0.1)
				(type default)
			)
			(layer "B.SilkS")
		)
		(fp_poly
			(pts
				(xy 0.970026 0.4699) (xy -0.970026 0.4699) (xy -0.970026 -0.4699) (xy 0.970026 -0.4699)
			)
			(stroke
				(width 0)
				(type default)
			)
			(fill no)
			(layer "B.CrtYd")
		)
		(fp_line
			(start -0.508 0.3048)
			(end 0.508 0.3048)
			(stroke
				(width 0.1)
				(type default)
			)
			(layer "B.Fab")
		)
		(fp_line
			(start 0.508 0.3048)
			(end 0.508 -0.3048)
			(stroke
				(width 0.1)
				(type default)
			)
			(layer "B.Fab")
		)
		(fp_line
			(start -0.508 -0.3048)
			(end -0.508 0.3048)
			(stroke
				(width 0.1)
				(type default)
			)
			(layer "B.Fab")
		)
		(fp_line
			(start 0.508 -0.3048)
			(end -0.508 -0.3048)
			(stroke
				(width 0.1)
				(type default)
			)
			(layer "B.Fab")
		)
		(pad "1" smd circle
			(at 0.500126 0 90)
			(size 0.635 0.635)
			(layers "B.Cu" "B.Mask" "B.Paste")
			(net "XP2R5V_FPGA")
		)
		(pad "2" smd circle
			(at -0.500126 0 90)
			(size 0.635 0.635)
			(layers "B.Cu" "B.Mask" "B.Paste")
			(net "SG")
		)
	)
)
